(kicad_pcb
	(version 20221018)
	(generator pcbnew)
	(general
    (thickness 1.6)
  )
	(paper "A4")
	(title_block
    (title "NUC Computer Cluster Power Breakout HW")
    (date "2023-10-18")
    (rev "1.4.3")
    (company "Antmicro Ltd.")
		(comment 9 "footprints 14-19 of 234")
	)
	(layers
    (0 "F.Cu" mixed)
    (1 "In1.Cu" power)
    (2 "In2.Cu" mixed)
    (31 "B.Cu" power)
    (32 "B.Adhes" user "B.Adhesive")
    (33 "F.Adhes" user "F.Adhesive")
    (34 "B.Paste" user)
    (35 "F.Paste" user)
    (36 "B.SilkS" user "B.Silkscreen")
    (37 "F.SilkS" user "F.Silkscreen")
    (38 "B.Mask" user)
    (39 "F.Mask" user)
    (40 "Dwgs.User" user "User.Drawings")
    (41 "Cmts.User" user "User.Comments")
    (42 "Eco1.User" user "User.Eco1")
    (43 "Eco2.User" user "User.Eco2")
    (44 "Edge.Cuts" user)
    (45 "Margin" user)
    (46 "B.CrtYd" user "B.Courtyard")
    (47 "F.CrtYd" user "F.Courtyard")
    (48 "B.Fab" user)
    (49 "F.Fab" user)
  )
	(footprint "antmicro-footprints:SOIC-8_3.9x4.9x1.75mm_P1.27mm" (layer "F.Cu")
    (at 114.35 82.05 180)
    (property "Author" "Antmicro")
    (property "License" "Apache-2.0")
    (property "MPN" "TMCS1100A2QDRQ1")
    (property "Manufacturer" "Texas Instruments")
    (property "Sheetfile" "pow-cycl-curr-meas.kicad_sch")
    (property "Sheetname" "Power Cycling & Current Measurement")
    (property "ki_description" "Hall current Sensor/transducer")
    (property "ki_keywords" "SMT, SENSOR, IC, POWER")
    (attr smd)
    (fp_text reference "U8" (at 4.4 1.55) (layer "F.SilkS")
        (effects (font (size 0.7 0.7) (thickness 0.15)) (justify right bottom))
    )
    (fp_text value "TMCS1100A2-Q1" (at 0 3.65) (layer "F.Fab")
        (effects (font (size 0.7 0.7) (thickness 0.15)) (justify right bottom))
    )
    (fp_text user "Author: Antmicro" (at -3.476 6.099) (layer "F.Fab") hide
        (effects (font (size 0.7 0.7) (thickness 0.15)) (justify right bottom))
    )
    (fp_text user "License: Apache-2.0" (at -3.476 5.099) (layer "F.Fab") hide
        (effects (font (size 0.7 0.7) (thickness 0.15)) (justify right bottom))
    )
    (fp_text user "${REFERENCE}" (at -3.476 7.099) (layer "F.Fab") hide
        (effects (font (size 0.7 0.7) (thickness 0.15)) (justify right bottom))
    )
    (fp_line (start -1.95 -2.452) (end 1.95 -2.45)
      (stroke (width 0.15) (type solid)) (layer "F.SilkS"))
    (fp_line (start -1.95 2.45) (end 1.95 2.45)
      (stroke (width 0.15) (type solid)) (layer "F.SilkS"))
    (fp_circle (center -2.4 -2.45) (end -2.35 -2.4)
      (stroke (width 0.15) (type solid)) (fill solid) (layer "F.SilkS"))
    (fp_rect (start -3.625 -2.7) (end 3.625 2.7)
      (stroke (width 0.05) (type solid)) (fill none) (layer "F.CrtYd"))
    (fp_line (start -1.95 -1.18) (end -0.683 -2.452)
      (stroke (width 0.15) (type solid)) (layer "F.Fab"))
    (fp_line (start -1.95 2.45) (end -1.95 -1.18)
      (stroke (width 0.15) (type solid)) (layer "F.Fab"))
    (fp_line (start -0.683 -2.452) (end 1.949 -2.452)
      (stroke (width 0.15) (type solid)) (layer "F.Fab"))
    (fp_line (start 1.949 -2.452) (end 1.949 2.45)
      (stroke (width 0.15) (type solid)) (layer "F.Fab"))
    (fp_line (start 1.949 2.45) (end -1.95 2.45)
      (stroke (width 0.15) (type solid)) (layer "F.Fab"))
    (pad "1" smd roundrect (at -2.714 -1.905 270) (size 0.65 1.525) (layers "F.Cu" "F.Paste" "F.Mask") (roundrect_rratio 0.25)
      (net 21 "C_MEAS_1") (pinfunction "IN+") (pintype "input"))
    (pad "2" smd roundrect (at -2.714 -0.635 270) (size 0.65 1.525) (layers "F.Cu" "F.Paste" "F.Mask") (roundrect_rratio 0.25)
      (net 21 "C_MEAS_1") (pinfunction "IN+") (pintype "input"))
    (pad "3" smd roundrect (at -2.714 0.632 270) (size 0.65 1.525) (layers "F.Cu" "F.Paste" "F.Mask") (roundrect_rratio 0.25)
      (net 41 "LOAD_1") (pinfunction "IN-") (pintype "input"))
    (pad "4" smd roundrect (at -2.714 1.902 270) (size 0.65 1.525) (layers "F.Cu" "F.Paste" "F.Mask") (roundrect_rratio 0.25)
      (net 41 "LOAD_1") (pinfunction "IN-") (pintype "input"))
    (pad "5" smd roundrect (at 2.712 1.902 270) (size 0.65 1.525) (layers "F.Cu" "F.Paste" "F.Mask") (roundrect_rratio 0.25)
      (net 4 "GND") (pinfunction "GND") (pintype "power_in"))
    (pad "6" smd roundrect (at 2.712 0.632 270) (size 0.65 1.525) (layers "F.Cu" "F.Paste" "F.Mask") (roundrect_rratio 0.25)
      (net 4 "GND") (pinfunction "VREF") (pintype "input"))
    (pad "7" smd roundrect (at 2.712 -0.635 270) (size 0.65 1.525) (layers "F.Cu" "F.Paste" "F.Mask") (roundrect_rratio 0.25)
      (net 46 "/Power Cycling & Current Measurement/C_ADC1") (pinfunction "VOUT") (pintype "output"))
    (pad "8" smd roundrect (at 2.712 -1.905 270) (size 0.65 1.525) (layers "F.Cu" "F.Paste" "F.Mask") (roundrect_rratio 0.25)
      (net 1 "VCC3V3") (pinfunction "VCC") (pintype "power_in"))
  )
	(footprint "antmicro-footprints:R_0402_1005Metric" (layer "F.Cu")
    (at 145.25 98.5 180)
    (descr "Resistor SMD 0402")
    (tags "resistor SMD 0402")
    (property "Author" "Antmicro")
    (property "Current" "1A")
    (property "License" "Apache-2.0")
    (property "MPN" "ERJ2GE0R00X")
    (property "Manufacturer" "Panasonic")
    (property "Sheetfile" "pow-cycl-curr-meas.kicad_sch")
    (property "Sheetname" "Power Cycling & Current Measurement")
    (property "Tolerance" "")
    (property "Val" "0R")
    (property "ki_description" "SMD Chip Resistor, Jumper, 0 ohm, 100 mW, 0402 [1005 Metric], Thick Film, General Purpose")
    (property "ki_keywords" "0402, SMT, RESISTOR, PASSIVE")
    (zone_connect 1)
    (attr smd)
    (fp_text reference "R31" (at 1 0.5 180) (layer "F.SilkS")
        (effects (font (size 0.7 0.7) (thickness 0.15)) (justify left bottom))
    )
    (fp_text value "R_0R_0402" (at -1.011843 1.772047 180) (layer "F.Fab")
        (effects (font (size 0.7 0.7) (thickness 0.15)) (justify left bottom))
    )
    (fp_text user "License: Apache-2.0" (at -0.95 5.169 180) (layer "F.Fab") hide
        (effects (font (size 0.7 0.7) (thickness 0.15)) (justify left bottom))
    )
    (fp_text user "Author: Antmicro" (at -0.95 4.169 180) (layer "F.Fab") hide
        (effects (font (size 0.7 0.7) (thickness 0.15)) (justify left bottom))
    )
    (fp_text user "${REFERENCE}" (at -0.95 3.168 180) (layer "F.Fab") hide
        (effects (font (size 0.7 0.7) (thickness 0.15)) (justify left bottom))
    )
    (fp_rect (start -0.925 -0.47) (end 0.925 0.47)
      (stroke (width 0.05) (type default)) (fill none) (layer "F.CrtYd"))
    (fp_rect (start -0.5 -0.25) (end 0.5 0.25)
      (stroke (width 0.15) (type solid)) (fill none) (layer "F.Fab"))
    (pad "1" smd roundrect (at -0.48 0 180) (size 0.59 0.64) (layers "F.Cu" "F.Paste" "F.Mask") (roundrect_rratio 0.25)
      (net 109 "Net-(U14-A1)") (pintype "passive"))
    (pad "2" smd roundrect (at 0.48 0 180) (size 0.59 0.64) (layers "F.Cu" "F.Paste" "F.Mask") (roundrect_rratio 0.25)
      (net 4 "GND") (pintype "passive"))
  )
	(footprint "antmicro-footprints:R_0402_1005Metric" (layer "F.Cu")
    (at 160.5 87)
    (descr "Resistor SMD 0402")
    (tags "resistor SMD 0402")
    (property "Author" "Antmicro")
    (property "License" "Apache-2.0")
    (property "MPN" "CR0402-FX-1002GLF")
    (property "Manufacturer" "Bourns")
    (property "Sheetfile" "power-switch.kicad_sch")
    (property "Sheetname" "Power switch 4")
    (property "Tolerance" "1%")
    (property "Val" "10k")
    (property "ki_description" "SMD Chip Resistor, 10 kohm, ± 1%, 62.5 mW, 0402 [1005 Metric], Thick Film, General Purpose")
    (property "ki_keywords" "0402, SMT, RESISTOR, PASSIVE")
    (attr smd)
    (fp_text reference "R26" (at -2 0.1) (layer "F.SilkS")
        (effects (font (size 0.7 0.7) (thickness 0.15)))
    )
    (fp_text value "R_10k_0402" (at 0 1.17) (layer "F.Fab") hide
        (effects (font (size 1 1) (thickness 0.15)))
    )
    (fp_text user "Author: Antmicro" (at -0.95 4.169) (layer "F.Fab") hide
        (effects (font (size 0.7 0.7) (thickness 0.15)) (justify left bottom))
    )
    (fp_text user "${REFERENCE}" (at 0 0) (layer "F.Fab")
        (effects (font (size 0.7 0.7) (thickness 0.15)))
    )
    (fp_text user "License: Apache-2.0" (at -0.95 5.169) (layer "F.Fab") hide
        (effects (font (size 0.7 0.7) (thickness 0.15)) (justify left bottom))
    )
    (fp_rect (start -0.925 -0.47) (end 0.925 0.47)
      (stroke (width 0.05) (type default)) (fill none) (layer "F.CrtYd"))
    (fp_rect (start -0.5 -0.25) (end 0.5 0.25)
      (stroke (width 0.15) (type solid)) (fill none) (layer "F.Fab"))
    (pad "1" smd roundrect (at -0.48 0) (size 0.59 0.64) (layers "F.Cu" "F.Paste" "F.Mask") (roundrect_rratio 0.25)
      (net 1 "VCC3V3") (pintype "passive"))
    (pad "2" smd roundrect (at 0.48 0) (size 0.59 0.64) (layers "F.Cu" "F.Paste" "F.Mask") (roundrect_rratio 0.25)
      (net 29 "/Power Cycling & Current Measurement/PC_4") (pintype "passive"))
  )
	(footprint "antmicro-footprints:R_0402_1005Metric" (layer "F.Cu")
    (at 126.9 86.9)
    (descr "Resistor SMD 0402")
    (tags "resistor SMD 0402")
    (property "Author" "Antmicro")
    (property "License" "Apache-2.0")
    (property "MPN" "CR0402-FX-1002GLF")
    (property "Manufacturer" "Bourns")
    (property "Sheetfile" "power-switch.kicad_sch")
    (property "Sheetname" "Power switch 2")
    (property "Tolerance" "1%")
    (property "Val" "10k")
    (property "ki_description" "SMD Chip Resistor, 10 kohm, ± 1%, 62.5 mW, 0402 [1005 Metric], Thick Film, General Purpose")
    (property "ki_keywords" "0402, SMT, RESISTOR, PASSIVE")
    (attr smd)
    (fp_text reference "R21" (at -0.9 1.3) (layer "F.SilkS")
        (effects (font (size 0.7 0.7) (thickness 0.15)) (justify left bottom))
    )
    (fp_text value "R_10k_0402" (at -1.011843 1.772047) (layer "F.Fab")
        (effects (font (size 0.7 0.7) (thickness 0.15)) (justify left bottom))
    )
    (fp_text user "Author: Antmicro" (at -0.95 4.169) (layer "F.Fab") hide
        (effects (font (size 0.7 0.7) (thickness 0.15)) (justify left bottom))
    )
    (fp_text user "${REFERENCE}" (at -0.95 3.168) (layer "F.Fab") hide
        (effects (font (size 0.7 0.7) (thickness 0.15)) (justify left bottom))
    )
    (fp_text user "License: Apache-2.0" (at -0.95 5.169) (layer "F.Fab") hide
        (effects (font (size 0.7 0.7) (thickness 0.15)) (justify left bottom))
    )
    (fp_rect (start -0.925 -0.47) (end 0.925 0.47)
      (stroke (width 0.05) (type default)) (fill none) (layer "F.CrtYd"))
    (fp_rect (start -0.5 -0.25) (end 0.5 0.25)
      (stroke (width 0.15) (type solid)) (fill none) (layer "F.Fab"))
    (pad "1" smd roundrect (at -0.48 0) (size 0.59 0.64) (layers "F.Cu" "F.Paste" "F.Mask") (roundrect_rratio 0.25)
      (net 1 "VCC3V3") (pintype "passive"))
    (pad "2" smd roundrect (at 0.48 0) (size 0.59 0.64) (layers "F.Cu" "F.Paste" "F.Mask") (roundrect_rratio 0.25)
      (net 24 "/Power Cycling & Current Measurement/PC_2") (pintype "passive"))
  )
	(footprint "antmicro-footprints:R_0402_1005Metric" (layer "F.Cu")
    (at 145.75 101 90)
    (descr "Resistor SMD 0402")
    (tags "resistor SMD 0402")
    (property "Author" "Antmicro")
    (property "Current" "1A")
    (property "DNP" "DNP")
    (property "License" "Apache-2.0")
    (property "MPN" "ERJ2GE0R00X")
    (property "Manufacturer" "Panasonic")
    (property "Sheetfile" "pow-cycl-curr-meas.kicad_sch")
    (property "Sheetname" "Power Cycling & Current Measurement")
    (property "Tolerance" "")
    (property "Val" "0R")
    (property "dnp" "")
    (property "exclude_from_bom" "")
    (property "ki_description" "SMD Chip Resistor, Jumper, 0 ohm, 100 mW, 0402 [1005 Metric], Thick Film, General Purpose")
    (property "ki_keywords" "0402, SMT, RESISTOR, PASSIVE")
    (attr smd exclude_from_bom)
    (fp_text reference "R30" (at -3.1 0.4 90) (layer "F.SilkS")
        (effects (font (size 0.7 0.7) (thickness 0.15)) (justify left bottom))
    )
    (fp_text value "R_0R_0402" (at -1.011843 1.772047 90) (layer "F.Fab")
        (effects (font (size 0.7 0.7) (thickness 0.15)) (justify left bottom))
    )
    (fp_text user "${REFERENCE}" (at -0.95 3.168 90) (layer "F.Fab") hide
        (effects (font (size 0.7 0.7) (thickness 0.15)) (justify left bottom))
    )
    (fp_text user "License: Apache-2.0" (at -0.95 5.169 90) (layer "F.Fab") hide
        (effects (font (size 0.7 0.7) (thickness 0.15)) (justify left bottom))
    )
    (fp_text user "Author: Antmicro" (at -0.95 4.169 90) (layer "F.Fab") hide
        (effects (font (size 0.7 0.7) (thickness 0.15)) (justify left bottom))
    )
    (fp_rect (start -0.925 -0.47) (end 0.925 0.47)
      (stroke (width 0.05) (type default)) (fill none) (layer "F.CrtYd"))
    (fp_rect (start -0.5 -0.25) (end 0.5 0.25)
      (stroke (width 0.15) (type solid)) (fill none) (layer "F.Fab"))
    (pad "1" smd roundrect (at -0.48 0 90) (size 0.59 0.64) (layers "F.Cu" "F.Paste" "F.Mask") (roundrect_rratio 0.25)
      (net 1 "VCC3V3") (pintype "passive"))
    (pad "2" smd roundrect (at 0.48 0 90) (size 0.59 0.64) (layers "F.Cu" "F.Paste" "F.Mask") (roundrect_rratio 0.25)
      (net 109 "Net-(U14-A1)") (pintype "passive"))
  )
	(footprint "antmicro-footprints:SOT-23-3" (layer "F.Cu")
    (at 177.65 88.7)
    (property "Author" "Antmicro")
    (property "License" "Apache-2.0")
    (property "MPN" "2N7002")
    (property "Manufacturer" "ON Semiconductor")
    (property "Sheetfile" "power-switch.kicad_sch")
    (property "Sheetname" "Power switch 5")
    (property "ki_description" "Power MOSFET, N Channel, 60 V, 115 mA, 1.2 ohm, SOT-23, Surface Mount")
    (property "ki_keywords" "SMT, TRANSISTOR, SEMICONDUCTOR, NMOS")
    (attr smd)
    (fp_text reference "Q10" (at -3.05 2.95) (layer "F.SilkS")
        (effects (font (size 0.7 0.7) (thickness 0.15)) (justify left bottom))
    )
    (fp_text value "2N7002_SOT-23-3" (at -1.9 2.7) (layer "F.Fab")
        (effects (font (size 0.7 0.7) (thickness 0.15)) (justify left bottom))
    )
    (fp_text user "${REFERENCE}" (at -1.837 4) (layer "F.Fab") hide
        (effects (font (size 0.7 0.7) (thickness 0.15)) (justify left bottom))
    )
    (fp_text user "Author: Antmicro" (at -1.837 5.3) (layer "F.Fab") hide
        (effects (font (size 0.7 0.7) (thickness 0.15)) (justify left bottom))
    )
    (fp_text user "License: Apache-2.0" (at -1.8 6.8) (layer "F.Fab") hide
        (effects (font (size 0.7 0.7) (thickness 0.15)) (justify left bottom))
    )
    (fp_line (start -1.45 -1.35) (end -0.85 -1.35)
      (stroke (width 0.15) (type solid)) (layer "F.SilkS"))
    (fp_line (start -0.85 -1.35) (end -0.7 -1.5)
      (stroke (width 0.15) (type solid)) (layer "F.SilkS"))
    (fp_line (start -0.7 1.5) (end -0.7 1.35)
      (stroke (width 0.15) (type solid)) (layer "F.SilkS"))
    (fp_line (start 0.7 -1.5) (end -0.7 -1.5)
      (stroke (width 0.15) (type solid)) (layer "F.SilkS"))
    (fp_line (start 0.7 -0.4) (end 0.7 -1.5)
      (stroke (width 0.15) (type solid)) (layer "F.SilkS"))
    (fp_line (start 0.7 0.4) (end 0.7 1.5)
      (stroke (width 0.15) (type solid)) (layer "F.SilkS"))
    (fp_line (start 0.7 1.5) (end -0.7 1.5)
      (stroke (width 0.15) (type solid)) (layer "F.SilkS"))
    (fp_line (start -1.75 -0.5) (end -1.75 -1.4)
      (stroke (width 0.05) (type solid)) (layer "F.CrtYd"))
    (fp_line (start -1.75 0.5) (end -0.85 0.5)
      (stroke (width 0.05) (type solid)) (layer "F.CrtYd"))
    (fp_line (start -1.75 1.4) (end -1.75 0.5)
      (stroke (width 0.05) (type solid)) (layer "F.CrtYd"))
    (fp_line (start -0.9 -1.6) (end -0.9 -1.4)
      (stroke (width 0.05) (type solid)) (layer "F.CrtYd"))
    (fp_line (start -0.9 -1.6) (end 0.825 -1.6)
      (stroke (width 0.05) (type solid)) (layer "F.CrtYd"))
    (fp_line (start -0.9 -1.4) (end -1.75 -1.4)
      (stroke (width 0.05) (type solid)) (layer "F.CrtYd"))
    (fp_line (start -0.85 -0.5) (end -1.75 -0.5)
      (stroke (width 0.05) (type solid)) (layer "F.CrtYd"))
    (fp_line (start -0.85 0.5) (end -0.85 -0.5)
      (stroke (width 0.05) (type solid)) (layer "F.CrtYd"))
    (fp_line (start -0.85 1.4) (end -1.75 1.4)
      (stroke (width 0.05) (type solid)) (layer "F.CrtYd"))
    (fp_line (start -0.85 1.65) (end -0.85 1.4)
      (stroke (width 0.05) (type solid)) (layer "F.CrtYd"))
    (fp_line (start 0.825 -1.6) (end 0.825 -0.45)
      (stroke (width 0.05) (type solid)) (layer "F.CrtYd"))
    (fp_line (start 0.825 -0.45) (end 1.75 -0.45)
      (stroke (width 0.05) (type solid)) (layer "F.CrtYd"))
    (fp_line (start 0.85 0.45) (end 0.85 1.65)
      (stroke (width 0.05) (type solid)) (layer "F.CrtYd"))
    (fp_line (start 0.85 1.65) (end -0.85 1.65)
      (stroke (width 0.05) (type solid)) (layer "F.CrtYd"))
    (fp_line (start 1.75 -0.45) (end 1.75 0.45)
      (stroke (width 0.05) (type solid)) (layer "F.CrtYd"))
    (fp_line (start 1.75 0.45) (end 0.85 0.45)
      (stroke (width 0.05) (type solid)) (layer "F.CrtYd"))
    (fp_line (start -0.712 -1.325) (end -0.712 1.523)
      (stroke (width 0.15) (type solid)) (layer "F.Fab"))
    (fp_line (start -0.712 1.519) (end 0.688 1.519)
      (stroke (width 0.15) (type solid)) (layer "F.Fab"))
    (fp_line (start -0.437 -1.526) (end -0.712 -1.325)
      (stroke (width 0.15) (type solid)) (layer "F.Fab"))
    (fp_line (start -0.437 -1.526) (end 0.688 -1.526)
      (stroke (width 0.15) (type solid)) (layer "F.Fab"))
    (fp_line (start 0.688 1.519) (end 0.688 -1.52)
      (stroke (width 0.15) (type solid)) (layer "F.Fab"))
    (pad "1" smd roundrect (at -1.1 -0.951) (size 1 0.6) (layers "F.Cu" "F.Paste" "F.Mask") (roundrect_rratio 0.15)
      (net 26 "/Power Cycling & Current Measurement/PC_5") (pinfunction "G") (pintype "passive"))
    (pad "2" smd roundrect (at -1.1 0.949) (size 1 0.6) (layers "F.Cu" "F.Paste" "F.Mask") (roundrect_rratio 0.15)
      (net 4 "GND") (pinfunction "S") (pintype "passive"))
    (pad "3" smd roundrect (at 1.1 -0.0005) (size 1 0.6) (layers "F.Cu" "F.Paste" "F.Mask") (roundrect_rratio 0.15)
      (net 87 "Net-(D19-A)") (pinfunction "D") (pintype "passive"))
  )
)
